FILE_TYPE = CONNECTIVITY;
{Allegro Design Entry HDL 16.6-p007 (v16-6-112F) 10/10/2012}
"PAGE_NUMBER" = 55;
0"NC";
1"GND\g";
2"GND\g";
3"P3V3_STBY\g";
4"P3V3_STBY\g";
5"PVCCIO_CPU1\g";
6"PVCCIO_CPU1\g";
7"TP_CPU1_PROC_DIS_G_N";
8"M_L_CPU_VREF";
9"H_CPU1_MEMGHJ_MEMHOT_G_N";
10"CLK_100M_CPU1_BCLK1_DN";
11"M_M_CPU_VREF";
12"FM_CPU1_PKGID0";
13"CLK_100M_CPU1_BCLK2_DN";
14"FM_CPU1_PKGID1";
15"A_CPU1_GHJ_RCOMP2";
16"A_CPU1_GHJ_RCOMP0";
17"M_H_CPU_VREF";
18"H_CPU1_CATERR_G_N";
19"SVID_ALERT0_CPU1_R_N";
20"SVID_DIO0_CPU1_R";
21"SVID_ALERT1_CPU1_R_N";
22"SVID_DIO1_CPU1_R";
23"SVID_CLK1_CPU1_R";
24"SVID_CLK0_CPU1_R";
25"PU_CPU1_SOCKET_ID_0";
26"TP_CPU1_SOCKET_ID_2";
27"FM_CPU1_PROC_ID0";
28"XDP_CPU_OBSFN_B0_MBP6_N";
29"FM_CPU1_PKGID2";
30"FM_CPU1_PROC_ID1";
31"SVID_DIO1_CPU1";
32"SVID_CLK1_CPU1";
33"SVID_ALERT1_CPU1_N";
34"SVID_DIO0_CPU1";
35"SVID_CLK0_CPU1";
36"SVID_ALERT0_CPU1_N";
37"PECI_CPU_G";
38"PD_CPU1_EAR_N";
39"H_PM_SYNC_GTL_R2";
40"H_PMSYNC_CLK_24M_CPU1";
41"PWRGD_CPU1_DRAMPWROK_KLM_G";
42"A_CPU1_KLM_RCOMP1";
43"A_CPU1_KLM_RCOMP0";
44"A_CPU1_PE3_RBIAS";
45"A_CPU1_PE012_RBIAS";
46"A_CPU1_UPI01_RBIAS";
47"A_CPU1_UPI2_RBIAS";
48"TP_XDP_CPU1_OBSDATA_B1_MBP3_N";
49"XDP_CPU_OBSFN_B1_MBP7_N";
50"XDP_CPU_TCK0";
51"XDP_CPU1_TDI";
52"XDP_CPU_MBP0_N";
53"XDP_CPU_MBP1_N";
54"TP_XDP_CPU1_OBSDATA_B0_MBP2_N";
55"SMB_DDR_GHJ_SDA_G_R";
56"A_CPU1_KLM_RCOMP2";
57"A_CPU1_GHJ_RCOMP1";
58"M_GHJ_RST_N";
59"PWRGD_CPU1_DRAMPWROK_GHJ_G";
60"CLK_100M_CPU1_BCLK1_DP";
61"CLK_100M_CPU1_BCLK0_DN";
62"CLK_100M_CPU1_BCLK0_DP";
63"H_CPU1_ERR1_G_N";
64"PWRGD_CPU1_G";
65"PU_CPU1_TSC_SYNC";
66"PD_CPU1_TEST13";
67"PD_CPU1_TEST14";
68"TP_XDP_CPU1_OBSDATA_B3_MBP5_N";
69"TP_XDP_CPU1_OBSDATA_B2_MBP4_N";
70"A_CPU1_MCP01_RBIAS";
71"H_PM_SYNC_GTL";
72"H_CPU1_ERR0_G_N";
73"H_CPU1_ERR2_G_N";
74"RST_CPU1_G_N";
75"SMB_PIROM_CPU1_SDA";
76"SMB_PIROM_CPU1_SCL";
77"M_G_CPU_VREF";
78"M_J_CPU_VREF";
79"M_K_CPU_VREF";
80"XDP_CPU_TMS";
81"XDP_CPU_TRST_N";
82"CLK_100M_CPU1_BCLK2_DP";
83"M_KLM_RST_N";
84"H_CPU1_MEMKLM_MEMHOT_G_N";
85"SMB_DDR_KLM_SCL_G_R";
86"SMB_DDR_KLM_SDA_G_R";
87"SMB_CPU1_PE_HP_GTL_SDA";
88"SMB_DDR_GHJ_SCL_G_R";
89"SMB_CPU1_PE_HP_GTL_SCL";
90"PU_CPU1_TXT_AGENT";
91"H_CPU1_BMCINIT";
92"H_CPU1_THERMTRIP_G_N";
93"PU_CPU1_FRMAGENT";
94"PU_CPU1_SAFE_MODE_BOOT";
95"H_CPU1_PROCHOT_G_N";
96"H_CPU1_MSMI_G_N";
97"PD_CPU1_TEST12";
98"PU_CPU1_LEGACY_SKT";
99"TP_CPU1_NMI";
100"FM_CPU1_SM_WP";
101"H_PMSYNC_CLK_24M";
102"PD_CPU1_KSFC_DIS";
103"XDP_CPU_PREQ_N";
104"XDP_CPU_PRDY_N";
105"PD_PIROM_CPU1_ADDR2";
106"PD_PIROM_CPU1_ADDR1";
107"PU_PIROM_CPU1_ADDR0";
108"XDP_CPU1_TDO";
109"FM_CPU1_SKTOCC_LVT3_N";
110"PU_CPU1_SOCKET_ID_1";
111"H_CPU1_FAST_WAKE_N";
112"PD_CPU1_BIST_ENABLE";
113"PD_CPU1_TXT_PLTEN";
%"RES"
"2","(6575,2725)","2","mstr_discrete","I115";
;
CDS_SEC"1"
TOLERANCE"1%"
MATERIAL"CHIP"
LOCATION"R7P19"
VALUE"100.0"
WATTAGE"1/16W"
PART_NUMBER"G21796-017"
PACK_TYPE"0402"
SEC_TYPE"0402"
BOM_COST"PROC_SOCKET"
SEC"1"
CDS_LOCATION"R7P19"
ROOM"CPU1"
CDS_LIB"mstr_discrete";
"A"
$PN"1"15;
"B"
$PN"2"1;
%"RES"
"2","(7700,2525)","2","mstr_discrete","I116";
;
CDS_SEC"1"
PART_NUMBER"G21796-365"
LOCATION"R3D1"
VALUE"90.9"
TOLERANCE"1%"
PACK_TYPE"0402"
WATTAGE"1/16W"
MATERIAL"CHIP"
CDS_LIB"mstr_discrete"
SEC_TYPE"0402"
BOM_COST"PROC_SOCKET"
SEC"1"
CDS_LOCATION"R3D1"
ROOM"CPU1";
"A"
$PN"1"43;
"B"
$PN"2"1;
%"RES"
"2","(7475,2525)","2","mstr_discrete","I117";
;
CDS_SEC"1"
TOLERANCE"1%"
PACK_TYPE"0402"
MATERIAL"CHIP"
LOCATION"R3D2"
VALUE"90.9"
WATTAGE"1/16W"
PART_NUMBER"G21796-365"
ROOM"CPU1"
CDS_LOCATION"R3D2"
SEC_TYPE"0402"
BOM_COST"PROC_SOCKET"
SEC"1"
CDS_LIB"mstr_discrete";
"A"
$PN"1"42;
"B"
$PN"2"1;
%"RES"
"2","(7250,2525)","2","mstr_discrete","I118";
;
CDS_SEC"1"
PACK_TYPE"0402"
TOLERANCE"1%"
VALUE"100.0"
LOCATION"R3D3"
WATTAGE"1/16W"
MATERIAL"CHIP"
PART_NUMBER"G21796-017"
SEC_TYPE"0402"
BOM_COST"PROC_SOCKET"
SEC"1"
CDS_LOCATION"R3D3"
ROOM"CPU1"
CDS_LIB"mstr_discrete";
"A"
$PN"1"56;
"B"
$PN"2"1;
%"RES"
"2","(7025,2600)","2","mstr_discrete","I119";
;
CDS_SEC"1"
PACK_TYPE"0402"
PART_NUMBER"G21796-365"
MATERIAL"CHIP"
WATTAGE"1/16W"
TOLERANCE"1%"
VALUE"90.9"
LOCATION"R7P16"
SEC_TYPE"0402"
BOM_COST"PROC_SOCKET"
SEC"1"
ROOM"CPU1"
CDS_LOCATION"R7P16"
CDS_LIB"mstr_discrete";
"A"
$PN"1"16;
"B"
$PN"2"1;
%"GND"
"1","(6650,2250)","0","mstr_symbols","I121";
;
SIZE"1B"
HDL_POWER"GND"
VOLTAGE"0.0V"
CDS_LIB"mstr_symbols"
BODY_TYPE"PLUMBING";
"A\NAC"1;
%"GND"
"1","(6600,1100)","0","mstr_symbols","I122";
;
SIZE"1B"
HDL_POWER"GND"
BODY_TYPE"PLUMBING"
CDS_LIB"mstr_symbols"
VOLTAGE"0.0V";
"A\NAC"2;
%"RES"
"2","(6600,1425)","2","mstr_discrete","I123";
;
CDS_SEC"1"
LOCATION"R7P8"
VALUE"49.9"
TOLERANCE"1%"
MATERIAL"CHIP"
PACK_TYPE"0402"
PART_NUMBER"G21796-047"
WATTAGE"1/16W"
SEC_TYPE"0402"
BOM_COST"PROC_SOCKET"
SEC"1"
CDS_LOCATION"R7P8"
ROOM"CPU1"
CDS_LIB"mstr_discrete";
"A"
$PN"1"44;
"B"
$PN"2"2;
%"RES"
"2","(6825,1425)","2","mstr_discrete","I124";
;
CDS_SEC"1"
MATERIAL"CHIP"
VALUE"49.9"
PACK_TYPE"0402"
LOCATION"R7P10"
PART_NUMBER"G21796-047"
WATTAGE"1/16W"
TOLERANCE"1%"
SEC_TYPE"0402"
BOM_COST"PROC_SOCKET"
SEC"1"
CDS_LOCATION"R7P10"
ROOM"CPU1"
CDS_LIB"mstr_discrete";
"A"
$PN"1"45;
"B"
$PN"2"2;
%"RES"
"2","(7050,1425)","2","mstr_discrete","I125";
;
CDS_SEC"1"
LOCATION"R3D19"
TOLERANCE"1%"
PACK_TYPE"0402"
MATERIAL"CHIP"
WATTAGE"1/16W"
PART_NUMBER"G21796-047"
VALUE"49.9"
SEC_TYPE"0402"
BOM_COST"PROC_SOCKET"
SEC"1"
CDS_LOCATION"R3D19"
ROOM"CPU1"
CDS_LIB"mstr_discrete";
"A"
$PN"1"46;
"B"
$PN"2"2;
%"RES"
"2","(7275,1425)","2","mstr_discrete","I126";
;
CDS_SEC"1"
TOLERANCE"1%"
LOCATION"R7P11"
WATTAGE"1/16W"
MATERIAL"CHIP"
PACK_TYPE"0402"
PART_NUMBER"G21796-047"
VALUE"49.9"
SEC_TYPE"0402"
BOM_COST"PROC_SOCKET"
SEC"1"
CDS_LOCATION"R7P11"
ROOM"CPU1"
CDS_LIB"mstr_discrete";
"A"
$PN"1"47;
"B"
$PN"2"2;
%"RES"
"2","(6800,2650)","2","mstr_discrete","I140";
;
CDS_SEC"1"
TOLERANCE"1%"
LOCATION"R7P17"
VALUE"90.9"
PACK_TYPE"0402"
MATERIAL"CHIP"
PART_NUMBER"G21796-365"
WATTAGE"1/16W"
SEC_TYPE"0402"
ROOM"CPU1"
SEC"1"
BOM_COST"PROC_SOCKET"
CDS_LOCATION"R7P17"
CDS_LIB"mstr_discrete";
"A"
$PN"1"57;
"B"
$PN"2"1;
%"SOCKET_P_MECH_A"
"1","(6875,4000)","0","chpset_lib","I152";
;
LOCATION"XRU2"
SKT_NUMBER"P0"
MATERIAL"PLASTIC"
PACK_TYPE"RIGHT"
PART_NUMBER"H37604-101"
BOM_COST"PROC_SOCKET"
ROOM"CPU1"
CDS_LOCATION"XRU2"
CDS_LIB"chpset_lib";
%"SOCKET_P_MECH_A"
"1","(6875,3725)","0","chpset_lib","I153";
;
PACK_TYPE"LEFT"
PART_NUMBER"H37604-201"
LOCATION"XLU2"
SKT_NUMBER"P0"
MATERIAL"PLASTIC"
CDS_LIB"chpset_lib"
ROOM"CPU1"
CDS_LOCATION"XLU2"
BOM_COST"PROC_SOCKET";
%"RES"
"2","(7500,1425)","2","mstr_discrete","I155";
;
CDS_SEC"1"
PACK_TYPE"0402"
PART_NUMBER"G21796-047"
MATERIAL"CHIP"
WATTAGE"1/16W"
TOLERANCE"1%"
VALUE"49.9"
LOCATION"R3D4"
SEC_TYPE"0402"
BOM_COST"PROC_SOCKET"
SEC"1"
CDS_LOCATION"R3D4"
ROOM"CPU1"
CDS_LIB"mstr_discrete";
"A"
$PN"1"70;
"B"
$PN"2"2;
%"RES"
"1","(12100,3850)","0","mstr_discrete","I156";
;
CDS_SEC"1"
PACK_TYPE"0402"
WATTAGE"1/16W"
TOLERANCE"1%"
VALUE"49.9"
LOCATION"R7P26"
PART_NUMBER"G21796-047"
MATERIAL"CHIP"
SEC_TYPE"0402"
BOM_COST"PROC_SOCKET"
SEC"1"
ROOM"CPU1"
CDS_LOCATION"R7P26"
CDS_LIB"mstr_discrete";
"B"
$PN"2"101;
"A"
$PN"1"40;
%"RES"
"2","(12600,2300)","0","mstr_discrete","I157";
;
CDS_SEC"1"
MATERIAL"CHIP"
WATTAGE"1/16W"
VALUE"1.8K"
PACK_TYPE"0402"
TOLERANCE"1%"
LOCATION"R8N1"
PART_NUMBER"G21796-336"
SEC_TYPE"0402"
BOM_COST"PROC_SOCKET"
ROOM"CPU1"
CDS_LOCATION"R8N1"
SEC"1"
CDS_LIB"mstr_discrete";
"A"
$PN"1"3;
"B"
$PN"2"30;
%"RES"
"2","(12850,2300)","0","mstr_discrete","I158";
;
CDS_SEC"1"
LOCATION"R8N4"
VALUE"1.8K"
WATTAGE"1/16W"
MATERIAL"CHIP"
PACK_TYPE"0402"
TOLERANCE"1%"
PART_NUMBER"G21796-336"
SEC_TYPE"0402"
BOM_COST"PROC_SOCKET"
SEC"1"
ROOM"CPU1"
CDS_LOCATION"R8N4"
CDS_LIB"mstr_discrete";
"A"
$PN"1"3;
"B"
$PN"2"27;
%"RES"
"2","(13100,2300)","0","mstr_discrete","I159";
;
CDS_SEC"1"
VALUE"10.0K"
WATTAGE"1/16W"
TOLERANCE"1%"
LOCATION"R8N3"
PART_NUMBER"G21796-016"
MATERIAL"CHIP"
PACK_TYPE"0402"
SEC_TYPE"0402"
BOM_COST"PROC_SOCKET"
SEC"1"
ROOM"CPU1"
CDS_LOCATION"R8N3"
CDS_LIB"mstr_discrete";
"A"
$PN"1"3;
"B"
$PN"2"29;
%"RES"
"2","(13350,2300)","0","mstr_discrete","I160";
;
CDS_SEC"1"
WATTAGE"1/16W"
VALUE"10.0K"
LOCATION"R8N5"
TOLERANCE"1%"
PART_NUMBER"G21796-016"
PACK_TYPE"0402"
MATERIAL"CHIP"
SEC_TYPE"0402"
BOM_COST"PROC_SOCKET"
ROOM"CPU1"
SEC"1"
CDS_LOCATION"R8N5"
CDS_LIB"mstr_discrete";
"A"
$PN"1"3;
"B"
$PN"2"14;
%"RES"
"2","(13600,2300)","0","mstr_discrete","I161";
;
CDS_SEC"1"
VALUE"10.0K"
LOCATION"R8N2"
TOLERANCE"1%"
PART_NUMBER"G21796-016"
PACK_TYPE"0402"
MATERIAL"CHIP"
WATTAGE"1/16W"
BOM_COST"PROC_SOCKET"
SEC_TYPE"0402"
ROOM"CPU1"
SEC"1"
CDS_LOCATION"R8N2"
CDS_LIB"mstr_discrete";
"A"
$PN"1"3;
"B"
$PN"2"12;
%"P3V3_STBY"
"1","(13600,2600)","0","mstr_symbols","I162";
;
CDS_LIB"mstr_symbols"
SIZE"1B"
VOLTAGE"3.3V"
BODY_TYPE"PLUMBING"
HDL_POWER"P3V3_STBY";
"G\NAC"3;
%"P3V3_STBY"
"1","(13275,1325)","0","mstr_symbols","I169";
;
SIZE"1B"
VOLTAGE"3.3V"
CDS_LIB"mstr_symbols"
BODY_TYPE"PLUMBING"
HDL_POWER"P3V3_STBY";
"G\NAC"4;
%"RES"
"1","(12100,3900)","0","mstr_discrete","I170";
;
CDS_SEC"1"
TOLERANCE"1%"
VALUE"49.9"
LOCATION"R7P25"
WATTAGE"1/16W"
MATERIAL"CHIP"
PACK_TYPE"0402"
PART_NUMBER"G21796-047"
SEC"1"
SEC_TYPE"0402"
BOM_COST"PROC_SOCKET"
ROOM"CPU1"
CDS_LIB"mstr_discrete"
CDS_LOCATION"R7P25";
"B"
$PN"2"71;
"A"
$PN"1"39;
%"SKX_EXT_B"
"1","(10225,2500)","0","chpset_lib","I172";
;
CDS_SEC"1"
MATERIAL"IC"
LOCATION"U2D1"
PART_NUMBER"TBD"
PACK_TYPE"BGA1"
SEC_TYPE"BGA1"
SEC"1"
CDS_LOCATION"U2D1"
CDS_LIB"chpset_lib"
ROOM"CPU1";
"UPI2_RBIAS<0>"
$PN"CL28"47;
"UPI2_RBIAS<1>"
$PN"CK29"47;
"UPI01_RBIAS<0>"
$PN"AT29"46;
"UPI01_RBIAS<1>"
$PN"AP29"46;
"TXT_PLTEN"
$PN"AV15"113;
"TXT_AGENT"
$PN"AW18"90;
"TSC_SYNC"
$PN"AM11"65;
"TRST_N"
$PN"Y13"81;
"TMS"
$PN"W14"80;
"THERMTRIP_N"
$PN"AB15"92;
"TEST_15"
$PN"AW14"102;
"TEST_14"
$PN"DC50"67;
"TEST_13"
$PN"DB51"66;
"TEST_12"
$PN"AY19"97;
"TDO"
$PN"AE14"108;
"TDI"
$PN"AC14"51;
"TCK"
$PN"AA14"50;
"SVIDDATA<0>"
$PN"DB45"34;
"SVIDDATA<1>"
$PN"DJ44"31;
"SVIDCLK<0>"
$PN"DC44"35;
"SVIDCLK<1>"
$PN"DG44"32;
"SVIDALERT_N<0>"
$PN"DE44"36;
"SVIDALERT_N<1>"
$PN"DL44"33;
"SOCKET_ID<0>"
$PN"AU22"25;
"SOCKET_ID<1>"
$PN"AU16"110;
"SOCKET_ID<2>"
$PN"AU20"26;
"SM_WP"
$PN"CV59"100;
"SMBDAT"
$PN"CW58"75;
"SMBCLK"
$PN"CT59"76;
"SKTOCC_N"
$PN"AB13"109;
"SAFE_MODE_BOOT"
$PN"AR18"94;
"RESET_N"
$PN"AP21"74;
"PWRGOOD"
$PN"BC24"64;
"PROC_ID<0>"
$PN"CY71"27;
"PROC_ID<1>"
$PN"DB71"30;
"PROCHOT_N"
$PN"AC16"95;
"PROCDIS_N"
$PN"AB17"7;
"PREQ_N"
$PN"AR12"103;
"PRDY_N"
$PN"AG16"104;
"PM_FAST_WAKE_N"
$PN"AF15"111;
"PMSYNC_CLK"
$PN"AT19"40;
"PMSYNC"
$PN"AR14"39;
"PKGID<0>"
$PN"DC72"12;
"PKGID<1>"
$PN"CW72"14;
"PKGID<2>"
$PN"DA72"29;
"PIROM_ADDR<0>"
$PN"CU58"107;
"PIROM_ADDR<1>"
$PN"CV57"106;
"PIROM_ADDR<2>"
$PN"CW56"105;
"PE_HP_SDA"
$PN"AL18"87;
"PE_HP_SCL"
$PN"AM19"89;
"PECI"
$PN"AU12"37;
"PE3_RBIAS<0>"
$PN"CP29"44;
"PE3_RBIAS<1>"
$PN"CR30"44;
"PE012_RBIAS<0>"
$PN"CN30"45;
"PE012_RBIAS<1>"
$PN"CL30"45;
"NMI"
$PN"AP11"99;
"MSMI_N"
$PN"AN20"96;
"MEM_HOT_C345_N"
$PN"AF13"84;
"MEM_HOT_C012_N"
$PN"AH13"9;
"MCP01_RBIAS<0>"
$PN"CU32"70;
"MCP01_RBIAS<1>"
$PN"CT31"70;
"LEGACY_SKT"
$PN"AE20"98;
"FRMAGENT"
$PN"AV17"93;
"ERROR_N<0>"
$PN"AJ12"72;
"ERROR_N<1>"
$PN"AK11"63;
"ERROR_N<2>"
$PN"AL12"73;
"EAR_N"
$PN"AJ14"38;
"DDR5_CAVREF"
$PN"CV61"11;
"DDR4_CAVREF"
$PN"CT61"8;
"DDR3_CAVREF"
$PN"CP61"79;
"DDR345_SPDSDA"
$PN"AD17"86;
"DDR345_SPDSCL"
$PN"AE18"85;
"DDR345_RESET_N"
$PN"DV63"83;
"DDR345_RCOMP<0>"
$PN"DC48"43;
"DDR345_RCOMP<1>"
$PN"DD47"42;
"DDR345_RCOMP<2>"
$PN"DD49"56;
"DDR345_DRAM_PWR_OK"
$PN"CR28"41;
"DDR2_CAVREF"
$PN"AH63"78;
"DDR1_CAVREF"
$PN"AK63"17;
"DDR0_CAVREF"
$PN"AJ64"77;
"DDR012_SPDSDA"
$PN"AF17"55;
"DDR012_SPDSCL"
$PN"AJ18"88;
"DDR012_RESET_N"
$PN"U64"58;
"DDR012_RCOMP<0>"
$PN"Y43"16;
"DDR012_RCOMP<1>"
$PN"AB43"57;
"DDR012_RCOMP<2>"
$PN"AC42"15;
"DDR012_DRAM_PWR_OK"
$PN"AN30"59;
"CATERR_N"
$PN"AL14"18;
"BPM_N<0>"
$PN"AJ10"52;
"BPM_N<1>"
$PN"AH11"53;
"BPM_N<2>"
$PN"AG10"54;
"BPM_N<3>"
$PN"AF11"48;
"BPM_N<4>"
$PN"AA12"69;
"BPM_N<5>"
$PN"Y11"68;
"BPM_N<6>"
$PN"AE12"28;
"BPM_N<7>"
$PN"AC12"49;
"BMCINIT"
$PN"BD23"91;
"BIST_ENABLE"
$PN"BA20"112;
"BCLK2_DP"
$PN"CU26"82;
"BCLK2_DN"
$PN"CT25"13;
"BCLK1_DP"
$PN"CP27"60;
"BCLK1_DN"
$PN"CR26"10;
"BCLK0_DP"
$PN"AW24"62;
"BCLK0_DN"
$PN"AU24"61;
%"RES"
"2","(13275,1100)","0","mstr_discrete","I181";
;
CDS_SEC"1"
LOCATION"R6P39"
VALUE"4.75K"
TOLERANCE"1%"
MATERIAL"CHIP"
WATTAGE"1/16W"
PART_NUMBER"G21796-072"
PACK_TYPE"0402"
SEC_TYPE"0402"
SEC"1"
CDS_LOCATION"R6P39"
ROOM"CPU1"
CDS_LIB"mstr_discrete";
"A"
$PN"1"4;
"B"
$PN"2"109;
%"RES"
"2","(13600,3200)","0","mstr_discrete","I19";
;
CDS_SEC"1"
PART_NUMBER"G21796-047"
LOCATION"R3B2"
VALUE"49.9"
PACK_TYPE"0402"
TOLERANCE"1%"
WATTAGE"1/16W"
MATERIAL"CHIP"
CDS_LIB"mstr_discrete"
SEC_TYPE"0402"
BOM_COST"PROC_SOCKET"
SEC"1"
CDS_LOCATION"R3B2"
ROOM"CPU1";
"A"
$PN"1"19;
"B"
$PN"2"5;
%"RES"
"2","(13325,3200)","0","mstr_discrete","I21";
;
CDS_SEC"1"
LOCATION"R3B4"
VALUE"100.0"
MATERIAL"CHIP"
TOLERANCE"1%"
WATTAGE"1/16W"
PACK_TYPE"0402"
PART_NUMBER"G21796-017"
SEC"1"
CDS_LOCATION"R3B4"
ROOM"CPU1"
BOM_COST"PROC_SOCKET"
SEC_TYPE"0402"
CDS_LIB"mstr_discrete";
"A"
$PN"1"20;
"B"
$PN"2"5;
%"PVCCIO_CPU1"
"1","(13950,2975)","0","mstr_symbols","I22";
;
BODY_TYPE"PLUMBING"
VOLTAGE"1.1V"
CDS_LIB"mstr_symbols"
HDL_POWER"PVCCIO_CPU1";
"G\NAC"5;
%"RES"
"1","(12250,3650)","0","mstr_discrete","I24";
;
PART_NUMBER"G21497-005"
LOCATION"R1C2"
TOLERANCE"5%"
VALUE"0.0"
WATTAGE"1/16W"
PACK_TYPE"0402"
CDS_LOCATION"R1C2"
CDS_SEC"1"
$SEC"1"
MATERIAL"CHIP"
CDS_LIB"mstr_discrete"
BOM_COST"PROC_SOCKET"
ROOM"CPU1";
"B"
$PN"2"22;
"A"
$PN"1"31;
%"RES"
"1","(12250,3600)","0","mstr_discrete","I25";
;
PART_NUMBER"G21497-005"
TOLERANCE"5%"
LOCATION"R1C3"
VALUE"0.0"
PACK_TYPE"0402"
WATTAGE"1/16W"
CDS_LOCATION"R1C3"
CDS_SEC"1"
$SEC"1"
MATERIAL"CHIP"
CDS_LIB"mstr_discrete"
ROOM"CPU1"
BOM_COST"PROC_SOCKET";
"B"
$PN"2"23;
"A"
$PN"1"32;
%"RES"
"1","(12250,3550)","0","mstr_discrete","I26";
;
PART_NUMBER"G21796-271"
LOCATION"R1C1"
PACK_TYPE"0402"
TOLERANCE"1.0%"
VALUE"221"
WATTAGE"1/16W"
CDS_LOCATION"R1C1"
$SEC"1"
CDS_SEC"1"
MATERIAL"CHIP"
ROOM"CPU1"
CDS_LIB"mstr_discrete"
BOM_COST"PROC_SOCKET";
"B"
$PN"2"21;
"A"
$PN"1"33;
%"RES"
"1","(12250,3400)","0","mstr_discrete","I27";
;
PART_NUMBER"G21796-271"
LOCATION"R3B1"
VALUE"221"
PACK_TYPE"0402"
TOLERANCE"1.0%"
WATTAGE"1/16W"
CDS_LOCATION"R3B1"
CDS_SEC"1"
$SEC"1"
MATERIAL"CHIP"
CDS_LIB"mstr_discrete"
ROOM"CPU1"
BOM_COST"PROC_SOCKET";
"B"
$PN"2"19;
"A"
$PN"1"36;
%"RES"
"1","(12250,3450)","0","mstr_discrete","I28";
;
LOCATION"R3B5"
PART_NUMBER"G21497-005"
PACK_TYPE"0402"
VALUE"0.0"
TOLERANCE"5%"
WATTAGE"1/16W"
CDS_LOCATION"R3B5"
CDS_SEC"1"
$SEC"1"
CDS_LIB"mstr_discrete"
MATERIAL"CHIP"
ROOM"CPU1"
BOM_COST"PROC_SOCKET";
"B"
$PN"2"24;
"A"
$PN"1"35;
%"RES"
"1","(12250,3500)","0","mstr_discrete","I29";
;
PART_NUMBER"G21497-005"
LOCATION"R3B3"
VALUE"0.0"
PACK_TYPE"0402"
TOLERANCE"5%"
WATTAGE"1/16W"
CDS_LOCATION"R3B3"
$SEC"1"
CDS_SEC"1"
CDS_LIB"mstr_discrete"
MATERIAL"CHIP"
ROOM"CPU1"
BOM_COST"PROC_SOCKET";
"B"
$PN"2"20;
"A"
$PN"1"34;
%"RES"
"2","(13600,3925)","0","mstr_discrete","I4";
;
CDS_SEC"1"
LOCATION"R9N1"
VALUE"49.9"
WATTAGE"1/16W"
TOLERANCE"1%"
MATERIAL"CHIP"
PACK_TYPE"0402"
PART_NUMBER"G21796-047"
SEC_TYPE"0402"
BOM_COST"PROC_SOCKET"
SEC"1"
ROOM"CPU1"
CDS_LIB"mstr_discrete"
CDS_LOCATION"R9N1";
"A"
$PN"1"6;
"B"
$PN"2"21;
%"PVCCIO_CPU1"
"1","(13325,4275)","0","mstr_symbols","I6";
;
HDL_POWER"PVCCIO_CPU1"
CDS_LIB"mstr_symbols"
VOLTAGE"1.1V"
BODY_TYPE"PLUMBING";
"G\NAC"6;
%"RES"
"2","(13325,3925)","0","mstr_discrete","I7";
;
CDS_SEC"1"
VALUE"100.0"
LOCATION"R9N2"
WATTAGE"1/16W"
MATERIAL"CHIP"
PART_NUMBER"G21796-017"
PACK_TYPE"0402"
TOLERANCE"1%"
ROOM"CPU1"
SEC"1"
BOM_COST"PROC_SOCKET"
SEC_TYPE"0402"
CDS_LOCATION"R9N2"
CDS_LIB"mstr_discrete";
"A"
$PN"1"6;
"B"
$PN"2"22;
END.
